# SCM (Grand Teton) — schematic netlist excerpt (pin names and nets, part order shuffled) for the footprints in the layout excerpt that follows; sources: Cadence DE-HDL packaged netlist, KiCad conversion of 12092022_DA0F0TMDCD0_F0T_Management_Board_D_brd_V3_OCP.brd

C57  Q_CAP  0.1UF 25V 10% X7R  pkg 0402  page 17 : A = P3V3_P1V8_I2C_I3C ; B = GND
C99  Q_CAP  0.1UF 25V 10% X7R  pkg 0402  page 16 : A = P1V0_AUX ; B = GND

(kicad_pcb
	(version 20260206)
	(generator "pcbnew")
	(generator_version "10.0")
	(general
		(thickness 1.6)
		(legacy_teardrops no)
	)
	(paper "A4")
	(title_block
		(title "12092022_DA0F0TMDCD0_F0T_Management_Board_D_brd_V3_OCP.brd")
		(comment 1 "Grand Teton / footprints 795-796 of 1440")
	)
	(layers
		(0 "F.Cu" signal "TOP")
		(4 "In1.Cu" signal "GND")
		(6 "In2.Cu" signal "IN1")
		(8 "In3.Cu" signal "GND1")
		(10 "In4.Cu" signal "IN2")
		(12 "In5.Cu" signal "VCC")
		(14 "In6.Cu" signal "VCC1")
		(16 "In7.Cu" signal "IN3")
		(18 "In8.Cu" signal "GND2")
		(20 "In9.Cu" signal "IN4")
		(22 "In10.Cu" signal "GND3")
		(2 "B.Cu" signal "BOTTOM")
		(9 "F.Adhes" user "F.Adhesive")
		(11 "B.Adhes" user "B.Adhesive")
		(13 "F.Paste" user "Package Geometry/Pastemask Top")
		(15 "B.Paste" user "Package Geometry/Pastemask Bottom")
		(5 "F.SilkS" user "Ref Des/Silkscreen Top")
		(7 "B.SilkS" user "Ref Des/Silkscreen Bottom")
		(1 "F.Mask" user "Board Geometry/Soldermask Top")
		(3 "B.Mask" user "Board Geometry/Soldermask Bottom")
		(17 "Dwgs.User" user "User.Drawings")
		(19 "Cmts.User" user "User.Comments")
		(21 "Eco1.User" user "User.Eco1")
		(23 "Eco2.User" user "User.Eco2")
		(25 "Edge.Cuts" user "Board Geometry/Outline")
		(27 "Margin" user)
		(31 "F.CrtYd" user "Package Geometry/Place Bound Top")
		(29 "B.CrtYd" user "Package Geometry/Place Bound Bottom")
		(35 "F.Fab" user "Ref Des/Assembly Top")
		(33 "B.Fab" user "Ref Des/Assembly Bottom")
	)
	(footprint ""
		(layer "B.Cu")
		(at 56.43626 -47.606966 90)
		(property "Reference" "C99"
			(at 0 0 90)
			(layer "B.SilkS")
			(hide yes)
			(effects
				(font
					(size 1.27 1.27)
				)
				(justify mirror)
			)
		)
		(property "Value" ""
			(at 0 0 90)
			(layer "B.Fab")
			(effects
				(font
					(size 1.27 1.27)
				)
				(justify mirror)
			)
		)
		(duplicate_pad_numbers_are_jumpers no)
		(fp_line
			(start 0.7874 -0.4064)
			(end -0.7874 -0.4064)
			(stroke
				(width 0.1524)
				(type default)
			)
			(layer "B.SilkS")
		)
		(fp_line
			(start -0.7874 -0.4064)
			(end -0.7874 0.4064)
			(stroke
				(width 0.1524)
				(type default)
			)
			(layer "B.SilkS")
		)
		(fp_line
			(start 0.7874 0.4064)
			(end 0.7874 -0.4064)
			(stroke
				(width 0.1524)
				(type default)
			)
			(layer "B.SilkS")
		)
		(fp_line
			(start -0.7874 0.4064)
			(end 0.7874 0.4064)
			(stroke
				(width 0.1524)
				(type default)
			)
			(layer "B.SilkS")
		)
		(fp_line
			(start 0.67945 -0.305054)
			(end 0.12065 -0.305054)
			(stroke
				(width 0.1)
				(type default)
			)
			(layer "B.Fab")
		)
		(fp_line
			(start 0.12065 -0.305054)
			(end 0.12065 -0.2794)
			(stroke
				(width 0.1)
				(type default)
			)
			(layer "B.Fab")
		)
		(fp_line
			(start -0.12065 -0.3048)
			(end -0.67945 -0.3048)
			(stroke
				(width 0.1)
				(type default)
			)
			(layer "B.Fab")
		)
		(fp_line
			(start -0.67945 -0.3048)
			(end -0.67945 0.3048)
			(stroke
				(width 0.1)
				(type default)
			)
			(layer "B.Fab")
		)
		(fp_line
			(start 0.12065 -0.2794)
			(end -0.12065 -0.2794)
			(stroke
				(width 0.1)
				(type default)
			)
			(layer "B.Fab")
		)
		(fp_line
			(start -0.12065 -0.2794)
			(end -0.12065 -0.3048)
			(stroke
				(width 0.1)
				(type default)
			)
			(layer "B.Fab")
		)
		(fp_line
			(start 0.12065 0.2794)
			(end 0.12065 0.3048)
			(stroke
				(width 0.1)
				(type default)
			)
			(layer "B.Fab")
		)
		(fp_line
			(start -0.120396 0.2794)
			(end 0.12065 0.2794)
			(stroke
				(width 0.1)
				(type default)
			)
			(layer "B.Fab")
		)
		(fp_line
			(start 0.67945 0.3048)
			(end 0.67945 -0.305054)
			(stroke
				(width 0.1)
				(type default)
			)
			(layer "B.Fab")
		)
		(fp_line
			(start 0.12065 0.3048)
			(end 0.67945 0.3048)
			(stroke
				(width 0.1)
				(type default)
			)
			(layer "B.Fab")
		)
		(fp_line
			(start -0.120396 0.3048)
			(end -0.120396 0.2794)
			(stroke
				(width 0.1)
				(type default)
			)
			(layer "B.Fab")
		)
		(fp_line
			(start -0.67945 0.3048)
			(end -0.120396 0.3048)
			(stroke
				(width 0.1)
				(type default)
			)
			(layer "B.Fab")
		)
		(pad "1" smd circle
			(at 0.40005 0 270)
			(size 0 0)
			(layers "B.Cu" "B.Mask" "B.Paste")
			(net "P1V0_AUX")
		)
		(pad "2" smd circle
			(at -0.40005 0 270)
			(size 0 0)
			(layers "B.Cu" "B.Mask" "B.Paste")
			(net "GND")
		)
	)
	(footprint ""
		(layer "B.Cu")
		(at 50.155602 -43.303952 -90)
		(property "Reference" "C57"
			(at 0 0 90)
			(layer "B.SilkS")
			(hide yes)
			(effects
				(font
					(size 1.27 1.27)
				)
				(justify mirror)
			)
		)
		(property "Value" ""
			(at 0 0 90)
			(layer "B.Fab")
			(effects
				(font
					(size 1.27 1.27)
				)
				(justify mirror)
			)
		)
		(duplicate_pad_numbers_are_jumpers no)
		(fp_line
			(start -0.7874 0.4064)
			(end 0.7874 0.4064)
			(stroke
				(width 0.1524)
				(type default)
			)
			(layer "B.SilkS")
		)
		(fp_line
			(start 0.7874 0.4064)
			(end 0.7874 -0.4064)
			(stroke
				(width 0.1524)
				(type default)
			)
			(layer "B.SilkS")
		)
		(fp_line
			(start -0.7874 -0.4064)
			(end -0.7874 0.4064)
			(stroke
				(width 0.1524)
				(type default)
			)
			(layer "B.SilkS")
		)
		(fp_line
			(start 0.7874 -0.4064)
			(end -0.7874 -0.4064)
			(stroke
				(width 0.1524)
				(type default)
			)
			(layer "B.SilkS")
		)
		(fp_line
			(start -0.67945 0.3048)
			(end -0.120396 0.3048)
			(stroke
				(width 0.1)
				(type default)
			)
			(layer "B.Fab")
		)
		(fp_line
			(start -0.120396 0.3048)
			(end -0.120396 0.2794)
			(stroke
				(width 0.1)
				(type default)
			)
			(layer "B.Fab")
		)
		(fp_line
			(start 0.12065 0.3048)
			(end 0.67945 0.3048)
			(stroke
				(width 0.1)
				(type default)
			)
			(layer "B.Fab")
		)
		(fp_line
			(start 0.67945 0.3048)
			(end 0.67945 -0.305054)
			(stroke
				(width 0.1)
				(type default)
			)
			(layer "B.Fab")
		)
		(fp_line
			(start -0.120396 0.2794)
			(end 0.12065 0.2794)
			(stroke
				(width 0.1)
				(type default)
			)
			(layer "B.Fab")
		)
		(fp_line
			(start 0.12065 0.2794)
			(end 0.12065 0.3048)
			(stroke
				(width 0.1)
				(type default)
			)
			(layer "B.Fab")
		)
		(fp_line
			(start -0.12065 -0.2794)
			(end -0.12065 -0.3048)
			(stroke
				(width 0.1)
				(type default)
			)
			(layer "B.Fab")
		)
		(fp_line
			(start 0.12065 -0.2794)
			(end -0.12065 -0.2794)
			(stroke
				(width 0.1)
				(type default)
			)
			(layer "B.Fab")
		)
		(fp_line
			(start -0.67945 -0.3048)
			(end -0.67945 0.3048)
			(stroke
				(width 0.1)
				(type default)
			)
			(layer "B.Fab")
		)
		(fp_line
			(start -0.12065 -0.3048)
			(end -0.67945 -0.3048)
			(stroke
				(width 0.1)
				(type default)
			)
			(layer "B.Fab")
		)
		(fp_line
			(start 0.12065 -0.305054)
			(end 0.12065 -0.2794)
			(stroke
				(width 0.1)
				(type default)
			)
			(layer "B.Fab")
		)
		(fp_line
			(start 0.67945 -0.305054)
			(end 0.12065 -0.305054)
			(stroke
				(width 0.1)
				(type default)
			)
			(layer "B.Fab")
		)
		(pad "1" smd circle
			(at 0.40005 0 90)
			(size 0 0)
			(layers "B.Cu" "B.Mask" "B.Paste")
			(net "P3V3_P1V8_I2C_I3C")
		)
		(pad "2" smd circle
			(at -0.40005 0 90)
			(size 0 0)
			(layers "B.Cu" "B.Mask" "B.Paste")
			(net "GND")
		)
	)
)
